# S9S_MB_2U (Grand Teton) — schematic netlist excerpt (pin names and nets, part order shuffled) for the footprints in the layout excerpt that follows; sources: Cadence DE-HDL packaged netlist, KiCad conversion of 03242023_DA0F0TMBIJ0_F0T_Motherboard_J_brd_V01_OCP.brd

R1013  Q_RES  0 5% EMPTY  pkg 0402LF  page 209 : A = CLK_25M_PCH_CPU0_DP ; B = CLK_25M_NSSC_CPU0_DP
PR327  Q_RES  2.2 1% CHIP  pkg 0402LF  page 285 : A = PVCCIN_CPU1_PVCC ; B = PVCCIN_CPU1_VDD2

(kicad_pcb
	(version 20260206)
	(generator "pcbnew")
	(generator_version "10.0")
	(general
		(thickness 1.6)
		(legacy_teardrops no)
	)
	(paper "A4")
	(title_block
		(title "03242023_DA0F0TMBIJ0_F0T_Motherboard_J_brd_V01_OCP.brd")
		(comment 1 "Grand Teton / footprints 4442-4443 of 6105")
	)
	(layers
		(0 "F.Cu" signal "TOP")
		(4 "In1.Cu" signal "GND")
		(6 "In2.Cu" signal "IN1")
		(8 "In3.Cu" signal "GND1")
		(10 "In4.Cu" signal "IN2")
		(12 "In5.Cu" signal "GND2")
		(14 "In6.Cu" signal "IN3")
		(16 "In7.Cu" signal "GND3")
		(18 "In8.Cu" signal "VCC")
		(20 "In9.Cu" signal "VCC1")
		(22 "In10.Cu" signal "GND4")
		(24 "In11.Cu" signal "IN4")
		(26 "In12.Cu" signal "GND5")
		(28 "In13.Cu" signal "IN5")
		(30 "In14.Cu" signal "GND6")
		(32 "In15.Cu" signal "IN6")
		(34 "In16.Cu" signal "GND7")
		(2 "B.Cu" signal "BOTTOM")
		(9 "F.Adhes" user "F.Adhesive")
		(11 "B.Adhes" user "B.Adhesive")
		(13 "F.Paste" user "Package Geometry/Pastemask Top")
		(15 "B.Paste" user "Package Geometry/Pastemask Bottom")
		(5 "F.SilkS" user "Ref Des/Silkscreen Top")
		(7 "B.SilkS" user "Ref Des/Silkscreen Bottom")
		(1 "F.Mask" user "Board Geometry/Soldermask Top")
		(3 "B.Mask" user "Board Geometry/Soldermask Bottom")
		(17 "Dwgs.User" user "User.Drawings")
		(19 "Cmts.User" user "User.Comments")
		(21 "Eco1.User" user "User.Eco1")
		(23 "Eco2.User" user "User.Eco2")
		(25 "Edge.Cuts" user "Board Geometry/Outline")
		(27 "Margin" user)
		(31 "F.CrtYd" user "Package Geometry/Place Bound Top")
		(29 "B.CrtYd" user "Package Geometry/Place Bound Bottom")
		(35 "F.Fab" user "Ref Des/Assembly Top")
		(33 "B.Fab" user "Ref Des/Assembly Bottom")
	)
	(footprint ""
		(layer "B.Cu")
		(at 338.441792 -137.832338)
		(property "Reference" "R1013"
			(at 0 0 0)
			(layer "B.SilkS")
			(hide yes)
			(effects
				(font
					(size 1.27 1.27)
				)
				(justify mirror)
			)
		)
		(property "Value" ""
			(at 0 0 0)
			(layer "B.Fab")
			(effects
				(font
					(size 1.27 1.27)
				)
				(justify mirror)
			)
		)
		(duplicate_pad_numbers_are_jumpers no)
		(fp_line
			(start -0.7874 -0.4064)
			(end -0.7874 0.4064)
			(stroke
				(width 0.1524)
				(type default)
			)
			(layer "B.SilkS")
		)
		(fp_line
			(start -0.7874 0.4064)
			(end -0.281432 0.4064)
			(stroke
				(width 0.1524)
				(type default)
			)
			(layer "B.SilkS")
		)
		(fp_line
			(start 0.333248 0.4064)
			(end 0.7874 0.4064)
			(stroke
				(width 0.1524)
				(type default)
			)
			(layer "B.SilkS")
		)
		(fp_line
			(start 0.7874 -0.4064)
			(end -0.7874 -0.4064)
			(stroke
				(width 0.1524)
				(type default)
			)
			(layer "B.SilkS")
		)
		(fp_line
			(start 0.7874 -0.18161)
			(end 0.7874 -0.4064)
			(stroke
				(width 0.1524)
				(type default)
			)
			(layer "B.SilkS")
		)
		(fp_line
			(start 0.7874 0.4064)
			(end 0.7874 0.21971)
			(stroke
				(width 0.1524)
				(type default)
			)
			(layer "B.SilkS")
		)
		(fp_line
			(start -0.67945 -0.3048)
			(end -0.67945 0.3048)
			(stroke
				(width 0.1)
				(type default)
			)
			(layer "B.Fab")
		)
		(fp_line
			(start -0.67945 0.3048)
			(end -0.120396 0.3048)
			(stroke
				(width 0.1)
				(type default)
			)
			(layer "B.Fab")
		)
		(fp_line
			(start -0.12065 -0.3048)
			(end -0.67945 -0.3048)
			(stroke
				(width 0.1)
				(type default)
			)
			(layer "B.Fab")
		)
		(fp_line
			(start -0.12065 -0.2794)
			(end -0.12065 -0.3048)
			(stroke
				(width 0.1)
				(type default)
			)
			(layer "B.Fab")
		)
		(fp_line
			(start -0.120396 0.2794)
			(end 0.12065 0.2794)
			(stroke
				(width 0.1)
				(type default)
			)
			(layer "B.Fab")
		)
		(fp_line
			(start -0.120396 0.3048)
			(end -0.120396 0.2794)
			(stroke
				(width 0.1)
				(type default)
			)
			(layer "B.Fab")
		)
		(fp_line
			(start 0.12065 -0.305054)
			(end 0.12065 -0.2794)
			(stroke
				(width 0.1)
				(type default)
			)
			(layer "B.Fab")
		)
		(fp_line
			(start 0.12065 -0.2794)
			(end -0.12065 -0.2794)
			(stroke
				(width 0.1)
				(type default)
			)
			(layer "B.Fab")
		)
		(fp_line
			(start 0.12065 0.2794)
			(end 0.12065 0.3048)
			(stroke
				(width 0.1)
				(type default)
			)
			(layer "B.Fab")
		)
		(fp_line
			(start 0.12065 0.3048)
			(end 0.67945 0.3048)
			(stroke
				(width 0.1)
				(type default)
			)
			(layer "B.Fab")
		)
		(fp_line
			(start 0.67945 -0.305054)
			(end 0.12065 -0.305054)
			(stroke
				(width 0.1)
				(type default)
			)
			(layer "B.Fab")
		)
		(fp_line
			(start 0.67945 0.3048)
			(end 0.67945 -0.305054)
			(stroke
				(width 0.1)
				(type default)
			)
			(layer "B.Fab")
		)
		(pad "1" smd rect
			(at 0.40005 0)
			(size 0.4572 0.508)
			(layers "B.Cu" "B.Mask" "B.Paste")
			(net "CLK_25M_PCH_CPU0_DP")
		)
		(pad "2" smd rect
			(at -0.40005 0)
			(size 0.4572 0.508)
			(layers "B.Cu" "B.Mask" "B.Paste")
			(net "CLK_25M_NSSC_CPU0_DP")
		)
	)
	(footprint ""
		(layer "B.Cu")
		(at 102.909624 -334.845152 -90)
		(property "Reference" "PR327"
			(at 0 0 90)
			(layer "B.SilkS")
			(hide yes)
			(effects
				(font
					(size 1.27 1.27)
				)
				(justify mirror)
			)
		)
		(property "Value" ""
			(at 0 0 90)
			(layer "B.Fab")
			(effects
				(font
					(size 1.27 1.27)
				)
				(justify mirror)
			)
		)
		(duplicate_pad_numbers_are_jumpers no)
		(fp_line
			(start -0.7874 0.4064)
			(end 0.7874 0.4064)
			(stroke
				(width 0.1524)
				(type default)
			)
			(layer "B.SilkS")
		)
		(fp_line
			(start 0.7874 0.4064)
			(end 0.7874 -0.4064)
			(stroke
				(width 0.1524)
				(type default)
			)
			(layer "B.SilkS")
		)
		(fp_line
			(start -0.7874 -0.4064)
			(end -0.7874 0.4064)
			(stroke
				(width 0.1524)
				(type default)
			)
			(layer "B.SilkS")
		)
		(fp_line
			(start 0.7874 -0.4064)
			(end -0.7874 -0.4064)
			(stroke
				(width 0.1524)
				(type default)
			)
			(layer "B.SilkS")
		)
		(fp_line
			(start -0.67945 0.3048)
			(end -0.120396 0.3048)
			(stroke
				(width 0.1)
				(type default)
			)
			(layer "B.Fab")
		)
		(fp_line
			(start -0.120396 0.3048)
			(end -0.120396 0.2794)
			(stroke
				(width 0.1)
				(type default)
			)
			(layer "B.Fab")
		)
		(fp_line
			(start 0.12065 0.3048)
			(end 0.67945 0.3048)
			(stroke
				(width 0.1)
				(type default)
			)
			(layer "B.Fab")
		)
		(fp_line
			(start 0.67945 0.3048)
			(end 0.67945 -0.305054)
			(stroke
				(width 0.1)
				(type default)
			)
			(layer "B.Fab")
		)
		(fp_line
			(start -0.120396 0.2794)
			(end 0.12065 0.2794)
			(stroke
				(width 0.1)
				(type default)
			)
			(layer "B.Fab")
		)
		(fp_line
			(start 0.12065 0.2794)
			(end 0.12065 0.3048)
			(stroke
				(width 0.1)
				(type default)
			)
			(layer "B.Fab")
		)
		(fp_line
			(start -0.12065 -0.2794)
			(end -0.12065 -0.3048)
			(stroke
				(width 0.1)
				(type default)
			)
			(layer "B.Fab")
		)
		(fp_line
			(start 0.12065 -0.2794)
			(end -0.12065 -0.2794)
			(stroke
				(width 0.1)
				(type default)
			)
			(layer "B.Fab")
		)
		(fp_line
			(start -0.67945 -0.3048)
			(end -0.67945 0.3048)
			(stroke
				(width 0.1)
				(type default)
			)
			(layer "B.Fab")
		)
		(fp_line
			(start -0.12065 -0.3048)
			(end -0.67945 -0.3048)
			(stroke
				(width 0.1)
				(type default)
			)
			(layer "B.Fab")
		)
		(fp_line
			(start 0.12065 -0.305054)
			(end 0.12065 -0.2794)
			(stroke
				(width 0.1)
				(type default)
			)
			(layer "B.Fab")
		)
		(fp_line
			(start 0.67945 -0.305054)
			(end 0.12065 -0.305054)
			(stroke
				(width 0.1)
				(type default)
			)
			(layer "B.Fab")
		)
		(pad "1" smd circle
			(at 0.40005 0 90)
			(size 0 0)
			(layers "B.Cu" "B.Mask" "B.Paste")
			(net "PVCCIN_CPU1_PVCC")
		)
		(pad "2" smd circle
			(at -0.40005 0 90)
			(size 0 0)
			(layers "B.Cu" "B.Mask" "B.Paste")
			(net "PVCCIN_CPU1_VDD2")
		)
	)
)
